# S9S_MB_2U (Grand Teton) — schematic netlist excerpt (pin names and nets, part order shuffled) for the footprints in the layout excerpt that follows; sources: Cadence DE-HDL packaged netlist, KiCad conversion of 03242023_DA0F0TMBIJ0_F0T_Motherboard_J_brd_V01_OCP.brd

R2666  Q_RES  10K 1% CHIP  pkg 0402LF  page 234 : A = SMB_BMC_SWB_EN ; B = GND

PR2533  Q_SP_RES4P  0.0003 1% EMPTY  pkg R2725_4P  page 304
  \1a\  = P12V_PSU
  \1b\  = P12V_HSC_SENSE2_R3_P
  \2a\  = P12V_MAIN_R
  \2b\  = P12V_HSC_SENSE2_R3_N

R4133  Q_RES  54.9K 1% EMPTY  pkg 0402LF  page 146 : A = P3V3_AUX ; B = GPU_3V3IO_RSVD5_FFU

(kicad_pcb
	(version 20260206)
	(generator "pcbnew")
	(generator_version "10.0")
	(general
		(thickness 1.6)
		(legacy_teardrops no)
	)
	(paper "A4")
	(title_block
		(title "03242023_DA0F0TMBIJ0_F0T_Motherboard_J_brd_V01_OCP.brd")
		(comment 1 "Grand Teton / footprints 88-90 of 6105")
	)
	(layers
		(0 "F.Cu" signal "TOP")
		(4 "In1.Cu" signal "GND")
		(6 "In2.Cu" signal "IN1")
		(8 "In3.Cu" signal "GND1")
		(10 "In4.Cu" signal "IN2")
		(12 "In5.Cu" signal "GND2")
		(14 "In6.Cu" signal "IN3")
		(16 "In7.Cu" signal "GND3")
		(18 "In8.Cu" signal "VCC")
		(20 "In9.Cu" signal "VCC1")
		(22 "In10.Cu" signal "GND4")
		(24 "In11.Cu" signal "IN4")
		(26 "In12.Cu" signal "GND5")
		(28 "In13.Cu" signal "IN5")
		(30 "In14.Cu" signal "GND6")
		(32 "In15.Cu" signal "IN6")
		(34 "In16.Cu" signal "GND7")
		(2 "B.Cu" signal "BOTTOM")
		(9 "F.Adhes" user "F.Adhesive")
		(11 "B.Adhes" user "B.Adhesive")
		(13 "F.Paste" user "Package Geometry/Pastemask Top")
		(15 "B.Paste" user "Package Geometry/Pastemask Bottom")
		(5 "F.SilkS" user "Ref Des/Silkscreen Top")
		(7 "B.SilkS" user "Ref Des/Silkscreen Bottom")
		(1 "F.Mask" user "Board Geometry/Soldermask Top")
		(3 "B.Mask" user "Board Geometry/Soldermask Bottom")
		(17 "Dwgs.User" user "User.Drawings")
		(19 "Cmts.User" user "User.Comments")
		(21 "Eco1.User" user "User.Eco1")
		(23 "Eco2.User" user "User.Eco2")
		(25 "Edge.Cuts" user "Board Geometry/Outline")
		(27 "Margin" user)
		(31 "F.CrtYd" user "Package Geometry/Place Bound Top")
		(29 "B.CrtYd" user "Package Geometry/Place Bound Bottom")
		(35 "F.Fab" user "Ref Des/Assembly Top")
		(33 "B.Fab" user "Ref Des/Assembly Bottom")
	)
	(footprint ""
		(layer "F.Cu")
		(at 252.780292 -407.416 -90)
		(property "Reference" "PR2533"
			(at 0 0 270)
			(layer "F.SilkS")
			(hide yes)
			(effects
				(font
					(size 1.27 1.27)
				)
			)
		)
		(property "Value" ""
			(at 0 0 270)
			(layer "F.Fab")
			(effects
				(font
					(size 1.27 1.27)
				)
			)
		)
		(duplicate_pad_numbers_are_jumpers no)
		(fp_line
			(start -3.9878 3.5814)
			(end -3.9878 -3.5814)
			(stroke
				(width 0.1524)
				(type default)
			)
			(layer "F.SilkS")
		)
		(fp_line
			(start 3.9878 3.5814)
			(end -3.9878 3.5814)
			(stroke
				(width 0.1524)
				(type default)
			)
			(layer "F.SilkS")
		)
		(fp_line
			(start -3.9878 -3.5814)
			(end 3.9878 -3.5814)
			(stroke
				(width 0.1524)
				(type default)
			)
			(layer "F.SilkS")
		)
		(fp_line
			(start 3.9878 -3.5814)
			(end 3.9878 3.5814)
			(stroke
				(width 0.1524)
				(type default)
			)
			(layer "F.SilkS")
		)
		(fp_line
			(start -3.5306 3.353054)
			(end -3.5306 -3.353054)
			(stroke
				(width 0.1)
				(type default)
			)
			(layer "F.Fab")
		)
		(fp_line
			(start 3.5306 3.353054)
			(end -3.5306 3.353054)
			(stroke
				(width 0.1)
				(type default)
			)
			(layer "F.Fab")
		)
		(fp_line
			(start -3.5306 -3.353054)
			(end 3.5306 -3.353054)
			(stroke
				(width 0.1)
				(type default)
			)
			(layer "F.Fab")
		)
		(fp_line
			(start 3.5306 -3.353054)
			(end 3.5306 3.353054)
			(stroke
				(width 0.1)
				(type default)
			)
			(layer "F.Fab")
		)
		(pad "1A" smd rect
			(at -2.249932 0 90)
			(size 3.2004 6.858)
			(layers "F.Cu" "F.Mask" "F.Paste")
			(net "P12V_PSU")
		)
		(pad "1B" smd rect
			(at -0.776732 0 270)
			(size 0.254 0.508)
			(layers "F.Cu" "F.Mask" "F.Paste")
			(net "P12V_HSC_SENSE2_R3_P")
		)
		(pad "2A" smd rect
			(at 2.249932 0 90)
			(size 3.2004 6.858)
			(layers "F.Cu" "F.Mask" "F.Paste")
			(net "P12V_MAIN_R")
		)
		(pad "2B" smd rect
			(at 0.776732 0 270)
			(size 0.254 0.508)
			(layers "F.Cu" "F.Mask" "F.Paste")
			(net "P12V_HSC_SENSE2_R3_N")
		)
	)
	(footprint ""
		(layer "F.Cu")
		(at 354.731828 -400.328638 180)
		(property "Reference" "R2666"
			(at 0 0 180)
			(layer "F.SilkS")
			(hide yes)
			(effects
				(font
					(size 1.27 1.27)
				)
			)
		)
		(property "Value" ""
			(at 0 0 180)
			(layer "F.Fab")
			(effects
				(font
					(size 1.27 1.27)
				)
			)
		)
		(duplicate_pad_numbers_are_jumpers no)
		(fp_line
			(start 0.7874 0.4064)
			(end -0.7874 0.4064)
			(stroke
				(width 0.1524)
				(type default)
			)
			(layer "F.SilkS")
		)
		(fp_line
			(start 0.7874 -0.4064)
			(end 0.7874 0.4064)
			(stroke
				(width 0.1524)
				(type default)
			)
			(layer "F.SilkS")
		)
		(fp_line
			(start -0.7874 0.4064)
			(end -0.7874 -0.4064)
			(stroke
				(width 0.1524)
				(type default)
			)
			(layer "F.SilkS")
		)
		(fp_line
			(start -0.7874 -0.4064)
			(end 0.7874 -0.4064)
			(stroke
				(width 0.1524)
				(type default)
			)
			(layer "F.SilkS")
		)
		(fp_line
			(start 0.67945 0.3048)
			(end 0.120396 0.3048)
			(stroke
				(width 0.1)
				(type default)
			)
			(layer "F.Fab")
		)
		(fp_line
			(start 0.67945 -0.3048)
			(end 0.67945 0.3048)
			(stroke
				(width 0.1)
				(type default)
			)
			(layer "F.Fab")
		)
		(fp_line
			(start 0.12065 -0.2794)
			(end 0.12065 -0.3048)
			(stroke
				(width 0.1)
				(type default)
			)
			(layer "F.Fab")
		)
		(fp_line
			(start 0.12065 -0.3048)
			(end 0.67945 -0.3048)
			(stroke
				(width 0.1)
				(type default)
			)
			(layer "F.Fab")
		)
		(fp_line
			(start 0.120396 0.3048)
			(end 0.120396 0.2794)
			(stroke
				(width 0.1)
				(type default)
			)
			(layer "F.Fab")
		)
		(fp_line
			(start 0.120396 0.2794)
			(end -0.12065 0.2794)
			(stroke
				(width 0.1)
				(type default)
			)
			(layer "F.Fab")
		)
		(fp_line
			(start -0.12065 0.3048)
			(end -0.67945 0.3048)
			(stroke
				(width 0.1)
				(type default)
			)
			(layer "F.Fab")
		)
		(fp_line
			(start -0.12065 0.2794)
			(end -0.12065 0.3048)
			(stroke
				(width 0.1)
				(type default)
			)
			(layer "F.Fab")
		)
		(fp_line
			(start -0.12065 -0.2794)
			(end 0.12065 -0.2794)
			(stroke
				(width 0.1)
				(type default)
			)
			(layer "F.Fab")
		)
		(fp_line
			(start -0.12065 -0.305054)
			(end -0.12065 -0.2794)
			(stroke
				(width 0.1)
				(type default)
			)
			(layer "F.Fab")
		)
		(fp_line
			(start -0.67945 0.3048)
			(end -0.67945 -0.305054)
			(stroke
				(width 0.1)
				(type default)
			)
			(layer "F.Fab")
		)
		(fp_line
			(start -0.67945 -0.305054)
			(end -0.12065 -0.305054)
			(stroke
				(width 0.1)
				(type default)
			)
			(layer "F.Fab")
		)
		(pad "1" smd circle
			(at -0.40005 0 180)
			(size 0 0)
			(layers "F.Cu" "F.Mask" "F.Paste")
			(net "SMB_BMC_SWB_EN")
		)
		(pad "2" smd circle
			(at 0.40005 0 180)
			(size 0 0)
			(layers "F.Cu" "F.Mask" "F.Paste")
			(net "GND")
		)
	)
	(footprint ""
		(layer "F.Cu")
		(at 297.41622 -421.41521 90)
		(property "Reference" "R4133"
			(at 0 0 90)
			(layer "F.SilkS")
			(hide yes)
			(effects
				(font
					(size 1.27 1.27)
				)
			)
		)
		(property "Value" ""
			(at 0 0 90)
			(layer "F.Fab")
			(effects
				(font
					(size 1.27 1.27)
				)
			)
		)
		(duplicate_pad_numbers_are_jumpers no)
		(fp_line
			(start 0.7874 -0.4064)
			(end 0.7874 0.4064)
			(stroke
				(width 0.1524)
				(type default)
			)
			(layer "F.SilkS")
		)
		(fp_line
			(start -0.7874 -0.4064)
			(end 0.7874 -0.4064)
			(stroke
				(width 0.1524)
				(type default)
			)
			(layer "F.SilkS")
		)
		(fp_line
			(start 0.7874 0.4064)
			(end -0.7874 0.4064)
			(stroke
				(width 0.1524)
				(type default)
			)
			(layer "F.SilkS")
		)
		(fp_line
			(start -0.7874 0.4064)
			(end -0.7874 -0.4064)
			(stroke
				(width 0.1524)
				(type default)
			)
			(layer "F.SilkS")
		)
		(fp_line
			(start -0.12065 -0.305054)
			(end -0.12065 -0.2794)
			(stroke
				(width 0.1)
				(type default)
			)
			(layer "F.Fab")
		)
		(fp_line
			(start -0.67945 -0.305054)
			(end -0.12065 -0.305054)
			(stroke
				(width 0.1)
				(type default)
			)
			(layer "F.Fab")
		)
		(fp_line
			(start 0.67945 -0.3048)
			(end 0.67945 0.3048)
			(stroke
				(width 0.1)
				(type default)
			)
			(layer "F.Fab")
		)
		(fp_line
			(start 0.12065 -0.3048)
			(end 0.67945 -0.3048)
			(stroke
				(width 0.1)
				(type default)
			)
			(layer "F.Fab")
		)
		(fp_line
			(start 0.12065 -0.2794)
			(end 0.12065 -0.3048)
			(stroke
				(width 0.1)
				(type default)
			)
			(layer "F.Fab")
		)
		(fp_line
			(start -0.12065 -0.2794)
			(end 0.12065 -0.2794)
			(stroke
				(width 0.1)
				(type default)
			)
			(layer "F.Fab")
		)
		(fp_line
			(start 0.120396 0.2794)
			(end -0.12065 0.2794)
			(stroke
				(width 0.1)
				(type default)
			)
			(layer "F.Fab")
		)
		(fp_line
			(start -0.12065 0.2794)
			(end -0.12065 0.3048)
			(stroke
				(width 0.1)
				(type default)
			)
			(layer "F.Fab")
		)
		(fp_line
			(start 0.67945 0.3048)
			(end 0.120396 0.3048)
			(stroke
				(width 0.1)
				(type default)
			)
			(layer "F.Fab")
		)
		(fp_line
			(start 0.120396 0.3048)
			(end 0.120396 0.2794)
			(stroke
				(width 0.1)
				(type default)
			)
			(layer "F.Fab")
		)
		(fp_line
			(start -0.12065 0.3048)
			(end -0.67945 0.3048)
			(stroke
				(width 0.1)
				(type default)
			)
			(layer "F.Fab")
		)
		(fp_line
			(start -0.67945 0.3048)
			(end -0.67945 -0.305054)
			(stroke
				(width 0.1)
				(type default)
			)
			(layer "F.Fab")
		)
		(pad "1" smd circle
			(at -0.40005 0 90)
			(size 0 0)
			(layers "F.Cu" "F.Mask" "F.Paste")
			(net "P3V3_AUX")
		)
		(pad "2" smd circle
			(at 0.40005 0 90)
			(size 0 0)
			(layers "F.Cu" "F.Mask" "F.Paste")
			(net "GPU_3V3IO_RSVD5_FFU")
		)
	)
)
